(kicad_pcb
	(version 20260206)
	(generator "pcbnew")
	(generator_version "10.0")
	(general
		(thickness 1.6)
		(legacy_teardrops no)
	)
	(paper "A4")
	(title_block
		(title "01162023_DA0F0TEBIF0_F0T_Expander_BD_F_brd_V02_OCP.brd")
		(comment 1 "Grand Teton / footprints 2440-2446 of 9728")
	)
	(layers
		(0 "F.Cu" signal "TOP")
		(4 "In1.Cu" signal "GND")
		(6 "In2.Cu" signal "VCC")
		(8 "In3.Cu" signal "VCC1")
		(10 "In4.Cu" signal "GND1")
		(12 "In5.Cu" signal "IN1")
		(14 "In6.Cu" signal "GND2")
		(16 "In7.Cu" signal "IN2")
		(18 "In8.Cu" signal "GND3")
		(20 "In9.Cu" signal "IN3")
		(22 "In10.Cu" signal "GND4")
		(24 "In11.Cu" signal "IN4")
		(26 "In12.Cu" signal "GND5")
		(28 "In13.Cu" signal "IN5")
		(30 "In14.Cu" signal "GND6")
		(32 "In15.Cu" signal "IN6")
		(34 "In16.Cu" signal "GND7")
		(2 "B.Cu" signal "BOTTOM")
		(9 "F.Adhes" user "F.Adhesive")
		(11 "B.Adhes" user "B.Adhesive")
		(13 "F.Paste" user "Package Geometry/Pastemask Top")
		(15 "B.Paste" user "Package Geometry/Pastemask Bottom")
		(5 "F.SilkS" user "Ref Des/Silkscreen Top")
		(7 "B.SilkS" user "Ref Des/Silkscreen Bottom")
		(1 "F.Mask" user "Board Geometry/Soldermask Top")
		(3 "B.Mask" user "Board Geometry/Soldermask Bottom")
		(17 "Dwgs.User" user "User.Drawings")
		(19 "Cmts.User" user "User.Comments")
		(21 "Eco1.User" user "User.Eco1")
		(23 "Eco2.User" user "User.Eco2")
		(25 "Edge.Cuts" user "Board Geometry/Outline")
		(27 "Margin" user)
		(31 "F.CrtYd" user "Package Geometry/Place Bound Top")
		(29 "B.CrtYd" user "Package Geometry/Place Bound Bottom")
		(35 "F.Fab" user "Ref Des/Assembly Top")
		(33 "B.Fab" user "Ref Des/Assembly Bottom")
	)
	(footprint ""
		(layer "F.Cu")
		(at 376.754898 -22.961346 90)
		(property "Reference" "R1715"
			(at 0 0 90)
			(layer "F.SilkS")
			(hide yes)
			(effects
				(font
					(size 1.27 1.27)
				)
			)
		)
		(property "Value" ""
			(at 0 0 90)
			(layer "F.Fab")
			(effects
				(font
					(size 1.27 1.27)
				)
			)
		)
		(duplicate_pad_numbers_are_jumpers no)
		(fp_line
			(start 0.7874 -0.4064)
			(end 0.7874 0.4064)
			(stroke
				(width 0.1524)
				(type default)
			)
			(layer "F.SilkS")
		)
		(fp_line
			(start -0.7874 -0.4064)
			(end 0.7874 -0.4064)
			(stroke
				(width 0.1524)
				(type default)
			)
			(layer "F.SilkS")
		)
		(fp_line
			(start 0.7874 0.4064)
			(end -0.7874 0.4064)
			(stroke
				(width 0.1524)
				(type default)
			)
			(layer "F.SilkS")
		)
		(fp_line
			(start -0.7874 0.4064)
			(end -0.7874 -0.4064)
			(stroke
				(width 0.1524)
				(type default)
			)
			(layer "F.SilkS")
		)
		(fp_line
			(start -0.12065 -0.305054)
			(end -0.12065 -0.2794)
			(stroke
				(width 0.1)
				(type default)
			)
			(layer "F.Fab")
		)
		(fp_line
			(start -0.67945 -0.305054)
			(end -0.12065 -0.305054)
			(stroke
				(width 0.1)
				(type default)
			)
			(layer "F.Fab")
		)
		(fp_line
			(start 0.67945 -0.3048)
			(end 0.67945 0.3048)
			(stroke
				(width 0.1)
				(type default)
			)
			(layer "F.Fab")
		)
		(fp_line
			(start 0.12065 -0.3048)
			(end 0.67945 -0.3048)
			(stroke
				(width 0.1)
				(type default)
			)
			(layer "F.Fab")
		)
		(fp_line
			(start 0.12065 -0.2794)
			(end 0.12065 -0.3048)
			(stroke
				(width 0.1)
				(type default)
			)
			(layer "F.Fab")
		)
		(fp_line
			(start -0.12065 -0.2794)
			(end 0.12065 -0.2794)
			(stroke
				(width 0.1)
				(type default)
			)
			(layer "F.Fab")
		)
		(fp_line
			(start 0.120396 0.2794)
			(end -0.12065 0.2794)
			(stroke
				(width 0.1)
				(type default)
			)
			(layer "F.Fab")
		)
		(fp_line
			(start -0.12065 0.2794)
			(end -0.12065 0.3048)
			(stroke
				(width 0.1)
				(type default)
			)
			(layer "F.Fab")
		)
		(fp_line
			(start 0.67945 0.3048)
			(end 0.120396 0.3048)
			(stroke
				(width 0.1)
				(type default)
			)
			(layer "F.Fab")
		)
		(fp_line
			(start 0.120396 0.3048)
			(end 0.120396 0.2794)
			(stroke
				(width 0.1)
				(type default)
			)
			(layer "F.Fab")
		)
		(fp_line
			(start -0.12065 0.3048)
			(end -0.67945 0.3048)
			(stroke
				(width 0.1)
				(type default)
			)
			(layer "F.Fab")
		)
		(fp_line
			(start -0.67945 0.3048)
			(end -0.67945 -0.305054)
			(stroke
				(width 0.1)
				(type default)
			)
			(layer "F.Fab")
		)
		(pad "1" smd circle
			(at -0.40005 0 90)
			(size 0 0)
			(layers "F.Cu" "F.Mask" "F.Paste")
			(net "SMB_SSD12_ISO_EN")
		)
		(pad "2" smd circle
			(at 0.40005 0 90)
			(size 0 0)
			(layers "F.Cu" "F.Mask" "F.Paste")
			(net "P3V3_AUX")
		)
	)
	(footprint ""
		(layer "F.Cu")
		(at 376.34926 -296.996612 -90)
		(property "Reference" "C3538"
			(at 0 0 270)
			(layer "F.SilkS")
			(hide yes)
			(effects
				(font
					(size 1.27 1.27)
				)
			)
		)
		(property "Value" ""
			(at 0 0 270)
			(layer "F.Fab")
			(effects
				(font
					(size 1.27 1.27)
				)
			)
		)
		(duplicate_pad_numbers_are_jumpers no)
		(fp_line
			(start -0.299974 0.150114)
			(end -0.299974 -0.150114)
			(stroke
				(width 0.1)
				(type default)
			)
			(layer "F.Fab")
		)
		(fp_line
			(start 0.299974 0.150114)
			(end -0.299974 0.150114)
			(stroke
				(width 0.1)
				(type default)
			)
			(layer "F.Fab")
		)
		(fp_line
			(start -0.299974 -0.150114)
			(end 0.299974 -0.150114)
			(stroke
				(width 0.1)
				(type default)
			)
			(layer "F.Fab")
		)
		(fp_line
			(start 0.299974 -0.150114)
			(end 0.299974 0.150114)
			(stroke
				(width 0.1)
				(type default)
			)
			(layer "F.Fab")
		)
		(pad "1" smd rect
			(at -0.2667 0 270)
			(size 0.3048 0.381)
			(layers "F.Cu" "F.Mask" "F.Paste")
			(net "P1V8_PLL0_PEX3")
		)
		(pad "2" smd rect
			(at 0.2667 0 270)
			(size 0.3048 0.381)
			(layers "F.Cu" "F.Mask" "F.Paste")
			(net "GND")
		)
	)
	(footprint ""
		(layer "F.Cu")
		(at 101.930454 -120.79224)
		(property "Reference" "R5863"
			(at 0 0 0)
			(layer "F.SilkS")
			(hide yes)
			(effects
				(font
					(size 1.27 1.27)
				)
			)
		)
		(property "Value" ""
			(at 0 0 0)
			(layer "F.Fab")
			(effects
				(font
					(size 1.27 1.27)
				)
			)
		)
		(duplicate_pad_numbers_are_jumpers no)
		(fp_line
			(start -0.7874 -0.4064)
			(end 0.7874 -0.4064)
			(stroke
				(width 0.1524)
				(type default)
			)
			(layer "F.SilkS")
		)
		(fp_line
			(start -0.7874 0.4064)
			(end -0.7874 -0.4064)
			(stroke
				(width 0.1524)
				(type default)
			)
			(layer "F.SilkS")
		)
		(fp_line
			(start 0.7874 -0.4064)
			(end 0.7874 0.4064)
			(stroke
				(width 0.1524)
				(type default)
			)
			(layer "F.SilkS")
		)
		(fp_line
			(start 0.7874 0.4064)
			(end -0.7874 0.4064)
			(stroke
				(width 0.1524)
				(type default)
			)
			(layer "F.SilkS")
		)
		(fp_line
			(start -0.67945 -0.305054)
			(end -0.12065 -0.305054)
			(stroke
				(width 0.1)
				(type default)
			)
			(layer "F.Fab")
		)
		(fp_line
			(start -0.67945 0.3048)
			(end -0.67945 -0.305054)
			(stroke
				(width 0.1)
				(type default)
			)
			(layer "F.Fab")
		)
		(fp_line
			(start -0.12065 -0.305054)
			(end -0.12065 -0.2794)
			(stroke
				(width 0.1)
				(type default)
			)
			(layer "F.Fab")
		)
		(fp_line
			(start -0.12065 -0.2794)
			(end 0.12065 -0.2794)
			(stroke
				(width 0.1)
				(type default)
			)
			(layer "F.Fab")
		)
		(fp_line
			(start -0.12065 0.2794)
			(end -0.12065 0.3048)
			(stroke
				(width 0.1)
				(type default)
			)
			(layer "F.Fab")
		)
		(fp_line
			(start -0.12065 0.3048)
			(end -0.67945 0.3048)
			(stroke
				(width 0.1)
				(type default)
			)
			(layer "F.Fab")
		)
		(fp_line
			(start 0.120396 0.2794)
			(end -0.12065 0.2794)
			(stroke
				(width 0.1)
				(type default)
			)
			(layer "F.Fab")
		)
		(fp_line
			(start 0.120396 0.3048)
			(end 0.120396 0.2794)
			(stroke
				(width 0.1)
				(type default)
			)
			(layer "F.Fab")
		)
		(fp_line
			(start 0.12065 -0.3048)
			(end 0.67945 -0.3048)
			(stroke
				(width 0.1)
				(type default)
			)
			(layer "F.Fab")
		)
		(fp_line
			(start 0.12065 -0.2794)
			(end 0.12065 -0.3048)
			(stroke
				(width 0.1)
				(type default)
			)
			(layer "F.Fab")
		)
		(fp_line
			(start 0.67945 -0.3048)
			(end 0.67945 0.3048)
			(stroke
				(width 0.1)
				(type default)
			)
			(layer "F.Fab")
		)
		(fp_line
			(start 0.67945 0.3048)
			(end 0.120396 0.3048)
			(stroke
				(width 0.1)
				(type default)
			)
			(layer "F.Fab")
		)
		(pad "1" smd circle
			(at -0.40005 0)
			(size 0 0)
			(layers "F.Cu" "F.Mask" "F.Paste")
			(net "P3V3_NIC1")
		)
		(pad "2" smd circle
			(at 0.40005 0)
			(size 0 0)
			(layers "F.Cu" "F.Mask" "F.Paste")
			(net "P3V3_NIC1_PG_G1")
		)
	)
	(footprint ""
		(layer "F.Cu")
		(at 136.534652 -30.03169 180)
		(property "Reference" "C281"
			(at 0 0 180)
			(layer "F.SilkS")
			(hide yes)
			(effects
				(font
					(size 1.27 1.27)
				)
			)
		)
		(property "Value" ""
			(at 0 0 180)
			(layer "F.Fab")
			(effects
				(font
					(size 1.27 1.27)
				)
			)
		)
		(duplicate_pad_numbers_are_jumpers no)
		(fp_line
			(start 0.299974 0.150114)
			(end -0.299974 0.150114)
			(stroke
				(width 0.1)
				(type default)
			)
			(layer "F.Fab")
		)
		(fp_line
			(start 0.299974 -0.150114)
			(end 0.299974 0.150114)
			(stroke
				(width 0.1)
				(type default)
			)
			(layer "F.Fab")
		)
		(fp_line
			(start -0.299974 0.150114)
			(end -0.299974 -0.150114)
			(stroke
				(width 0.1)
				(type default)
			)
			(layer "F.Fab")
		)
		(fp_line
			(start -0.299974 -0.150114)
			(end 0.299974 -0.150114)
			(stroke
				(width 0.1)
				(type default)
			)
			(layer "F.Fab")
		)
		(pad "1" smd rect
			(at -0.2667 0 180)
			(size 0.3048 0.381)
			(layers "F.Cu" "F.Mask" "F.Paste")
			(net "P5E_PEX1_STN2_TX_DN<45>")
		)
		(pad "2" smd rect
			(at 0.2667 0 180)
			(size 0.3048 0.381)
			(layers "F.Cu" "F.Mask" "F.Paste")
			(net "P5E_PEX1_STN2_TX_C_DN<45>")
		)
	)
	(footprint ""
		(layer "F.Cu")
		(at 437.323484 -96.811592 -90)
		(property "Reference" "R760"
			(at 0 0 270)
			(layer "F.SilkS")
			(hide yes)
			(effects
				(font
					(size 1.27 1.27)
				)
			)
		)
		(property "Value" ""
			(at 0 0 270)
			(layer "F.Fab")
			(effects
				(font
					(size 1.27 1.27)
				)
			)
		)
		(duplicate_pad_numbers_are_jumpers no)
		(fp_line
			(start -0.7874 0.4064)
			(end -0.7874 -0.4064)
			(stroke
				(width 0.1524)
				(type default)
			)
			(layer "F.SilkS")
		)
		(fp_line
			(start 0.7874 0.4064)
			(end -0.7874 0.4064)
			(stroke
				(width 0.1524)
				(type default)
			)
			(layer "F.SilkS")
		)
		(fp_line
			(start -0.7874 -0.4064)
			(end 0.7874 -0.4064)
			(stroke
				(width 0.1524)
				(type default)
			)
			(layer "F.SilkS")
		)
		(fp_line
			(start 0.7874 -0.4064)
			(end 0.7874 0.4064)
			(stroke
				(width 0.1524)
				(type default)
			)
			(layer "F.SilkS")
		)
		(fp_line
			(start -0.67945 0.3048)
			(end -0.67945 -0.305054)
			(stroke
				(width 0.1)
				(type default)
			)
			(layer "F.Fab")
		)
		(fp_line
			(start -0.12065 0.3048)
			(end -0.67945 0.3048)
			(stroke
				(width 0.1)
				(type default)
			)
			(layer "F.Fab")
		)
		(fp_line
			(start 0.120396 0.3048)
			(end 0.120396 0.2794)
			(stroke
				(width 0.1)
				(type default)
			)
			(layer "F.Fab")
		)
		(fp_line
			(start 0.67945 0.3048)
			(end 0.120396 0.3048)
			(stroke
				(width 0.1)
				(type default)
			)
			(layer "F.Fab")
		)
		(fp_line
			(start -0.12065 0.2794)
			(end -0.12065 0.3048)
			(stroke
				(width 0.1)
				(type default)
			)
			(layer "F.Fab")
		)
		(fp_line
			(start 0.120396 0.2794)
			(end -0.12065 0.2794)
			(stroke
				(width 0.1)
				(type default)
			)
			(layer "F.Fab")
		)
		(fp_line
			(start -0.12065 -0.2794)
			(end 0.12065 -0.2794)
			(stroke
				(width 0.1)
				(type default)
			)
			(layer "F.Fab")
		)
		(fp_line
			(start 0.12065 -0.2794)
			(end 0.12065 -0.3048)
			(stroke
				(width 0.1)
				(type default)
			)
			(layer "F.Fab")
		)
		(fp_line
			(start 0.12065 -0.3048)
			(end 0.67945 -0.3048)
			(stroke
				(width 0.1)
				(type default)
			)
			(layer "F.Fab")
		)
		(fp_line
			(start 0.67945 -0.3048)
			(end 0.67945 0.3048)
			(stroke
				(width 0.1)
				(type default)
			)
			(layer "F.Fab")
		)
		(fp_line
			(start -0.67945 -0.305054)
			(end -0.12065 -0.305054)
			(stroke
				(width 0.1)
				(type default)
			)
			(layer "F.Fab")
		)
		(fp_line
			(start -0.12065 -0.305054)
			(end -0.12065 -0.2794)
			(stroke
				(width 0.1)
				(type default)
			)
			(layer "F.Fab")
		)
		(pad "1" smd circle
			(at -0.40005 0 270)
			(size 0 0)
			(layers "F.Cu" "F.Mask" "F.Paste")
			(net "NIC7_ADC_A0")
		)
		(pad "2" smd circle
			(at 0.40005 0 270)
			(size 0 0)
			(layers "F.Cu" "F.Mask" "F.Paste")
			(net "P3V3_AUX")
		)
	)
	(footprint ""
		(layer "F.Cu")
		(at 33.77184 -24.807418)
		(property "Reference" "R413"
			(at 0 0 0)
			(layer "F.SilkS")
			(hide yes)
			(effects
				(font
					(size 1.27 1.27)
				)
			)
		)
		(property "Value" ""
			(at 0 0 0)
			(layer "F.Fab")
			(effects
				(font
					(size 1.27 1.27)
				)
			)
		)
		(duplicate_pad_numbers_are_jumpers no)
		(fp_line
			(start -0.7874 -0.4064)
			(end 0.7874 -0.4064)
			(stroke
				(width 0.1524)
				(type default)
			)
			(layer "F.SilkS")
		)
		(fp_line
			(start -0.7874 0.4064)
			(end -0.7874 -0.4064)
			(stroke
				(width 0.1524)
				(type default)
			)
			(layer "F.SilkS")
		)
		(fp_line
			(start 0.7874 -0.4064)
			(end 0.7874 0.4064)
			(stroke
				(width 0.1524)
				(type default)
			)
			(layer "F.SilkS")
		)
		(fp_line
			(start 0.7874 0.4064)
			(end -0.7874 0.4064)
			(stroke
				(width 0.1524)
				(type default)
			)
			(layer "F.SilkS")
		)
		(fp_line
			(start -0.67945 -0.305054)
			(end -0.12065 -0.305054)
			(stroke
				(width 0.1)
				(type default)
			)
			(layer "F.Fab")
		)
		(fp_line
			(start -0.67945 0.3048)
			(end -0.67945 -0.305054)
			(stroke
				(width 0.1)
				(type default)
			)
			(layer "F.Fab")
		)
		(fp_line
			(start -0.12065 -0.305054)
			(end -0.12065 -0.2794)
			(stroke
				(width 0.1)
				(type default)
			)
			(layer "F.Fab")
		)
		(fp_line
			(start -0.12065 -0.2794)
			(end 0.12065 -0.2794)
			(stroke
				(width 0.1)
				(type default)
			)
			(layer "F.Fab")
		)
		(fp_line
			(start -0.12065 0.2794)
			(end -0.12065 0.3048)
			(stroke
				(width 0.1)
				(type default)
			)
			(layer "F.Fab")
		)
		(fp_line
			(start -0.12065 0.3048)
			(end -0.67945 0.3048)
			(stroke
				(width 0.1)
				(type default)
			)
			(layer "F.Fab")
		)
		(fp_line
			(start 0.120396 0.2794)
			(end -0.12065 0.2794)
			(stroke
				(width 0.1)
				(type default)
			)
			(layer "F.Fab")
		)
		(fp_line
			(start 0.120396 0.3048)
			(end 0.120396 0.2794)
			(stroke
				(width 0.1)
				(type default)
			)
			(layer "F.Fab")
		)
		(fp_line
			(start 0.12065 -0.3048)
			(end 0.67945 -0.3048)
			(stroke
				(width 0.1)
				(type default)
			)
			(layer "F.Fab")
		)
		(fp_line
			(start 0.12065 -0.2794)
			(end 0.12065 -0.3048)
			(stroke
				(width 0.1)
				(type default)
			)
			(layer "F.Fab")
		)
		(fp_line
			(start 0.67945 -0.3048)
			(end 0.67945 0.3048)
			(stroke
				(width 0.1)
				(type default)
			)
			(layer "F.Fab")
		)
		(fp_line
			(start 0.67945 0.3048)
			(end 0.120396 0.3048)
			(stroke
				(width 0.1)
				(type default)
			)
			(layer "F.Fab")
		)
		(pad "1" smd circle
			(at -0.40005 0)
			(size 0 0)
			(layers "F.Cu" "F.Mask" "F.Paste")
			(net "P3V3_SSD1")
		)
		(pad "2" smd circle
			(at 0.40005 0)
			(size 0 0)
			(layers "F.Cu" "F.Mask" "F.Paste")
			(net "PU_CLKREQ1")
		)
	)
	(footprint ""
		(layer "F.Cu")
		(at 239.813338 -135.058404 180)
		(property "Reference" "C2854"
			(at 0 0 180)
			(layer "F.SilkS")
			(hide yes)
			(effects
				(font
					(size 1.27 1.27)
				)
			)
		)
		(property "Value" ""
			(at 0 0 180)
			(layer "F.Fab")
			(effects
				(font
					(size 1.27 1.27)
				)
			)
		)
		(duplicate_pad_numbers_are_jumpers no)
		(fp_line
			(start 0.7874 0.4064)
			(end -0.7874 0.4064)
			(stroke
				(width 0.1524)
				(type default)
			)
			(layer "F.SilkS")
		)
		(fp_line
			(start 0.7874 -0.4064)
			(end 0.7874 0.4064)
			(stroke
				(width 0.1524)
				(type default)
			)
			(layer "F.SilkS")
		)
		(fp_line
			(start -0.7874 0.4064)
			(end -0.7874 -0.4064)
			(stroke
				(width 0.1524)
				(type default)
			)
			(layer "F.SilkS")
		)
		(fp_line
			(start -0.7874 -0.4064)
			(end 0.7874 -0.4064)
			(stroke
				(width 0.1524)
				(type default)
			)
			(layer "F.SilkS")
		)
		(fp_line
			(start 0.67945 0.3048)
			(end 0.120396 0.3048)
			(stroke
				(width 0.1)
				(type default)
			)
			(layer "F.Fab")
		)
		(fp_line
			(start 0.67945 -0.3048)
			(end 0.67945 0.3048)
			(stroke
				(width 0.1)
				(type default)
			)
			(layer "F.Fab")
		)
		(fp_line
			(start 0.12065 -0.2794)
			(end 0.12065 -0.3048)
			(stroke
				(width 0.1)
				(type default)
			)
			(layer "F.Fab")
		)
		(fp_line
			(start 0.12065 -0.3048)
			(end 0.67945 -0.3048)
			(stroke
				(width 0.1)
				(type default)
			)
			(layer "F.Fab")
		)
		(fp_line
			(start 0.120396 0.3048)
			(end 0.120396 0.2794)
			(stroke
				(width 0.1)
				(type default)
			)
			(layer "F.Fab")
		)
		(fp_line
			(start 0.120396 0.2794)
			(end -0.12065 0.2794)
			(stroke
				(width 0.1)
				(type default)
			)
			(layer "F.Fab")
		)
		(fp_line
			(start -0.12065 0.3048)
			(end -0.67945 0.3048)
			(stroke
				(width 0.1)
				(type default)
			)
			(layer "F.Fab")
		)
		(fp_line
			(start -0.12065 0.2794)
			(end -0.12065 0.3048)
			(stroke
				(width 0.1)
				(type default)
			)
			(layer "F.Fab")
		)
		(fp_line
			(start -0.12065 -0.2794)
			(end 0.12065 -0.2794)
			(stroke
				(width 0.1)
				(type default)
			)
			(layer "F.Fab")
		)
		(fp_line
			(start -0.12065 -0.305054)
			(end -0.12065 -0.2794)
			(stroke
				(width 0.1)
				(type default)
			)
			(layer "F.Fab")
		)
		(fp_line
			(start -0.67945 0.3048)
			(end -0.67945 -0.305054)
			(stroke
				(width 0.1)
				(type default)
			)
			(layer "F.Fab")
		)
		(fp_line
			(start -0.67945 -0.305054)
			(end -0.12065 -0.305054)
			(stroke
				(width 0.1)
				(type default)
			)
			(layer "F.Fab")
		)
		(pad "1" smd circle
			(at -0.40005 0 180)
			(size 0 0)
			(layers "F.Cu" "F.Mask" "F.Paste")
			(net "P12V_NIC4_EN_R")
		)
		(pad "2" smd circle
			(at 0.40005 0 180)
			(size 0 0)
			(layers "F.Cu" "F.Mask" "F.Paste")
			(net "GND")
		)
	)
)
